(kicad_pcb
	(version 20260206)
	(generator "pcbnew")
	(generator_version "10.0")
	(general
		(thickness 1.6)
		(legacy_teardrops no)
	)
	(paper "A4")
	(title_block
		(title "Wiwynn_Tioga_Pass_MB.brd")
		(comment 1 "Tioga Pass / footprints 2868-2874 of 4770")
	)
	(layers
		(0 "F.Cu" signal "TOP")
		(4 "In1.Cu" signal "L2GND")
		(6 "In2.Cu" signal "L3")
		(8 "In3.Cu" signal "L4GND")
		(10 "In4.Cu" signal "L5")
		(12 "In5.Cu" signal "L6GND")
		(14 "In6.Cu" signal "L7VCC")
		(16 "In7.Cu" signal "L8VCC")
		(18 "In8.Cu" signal "L9GND")
		(20 "In9.Cu" signal "L10")
		(22 "In10.Cu" signal "L11GND")
		(24 "In11.Cu" signal "L12")
		(26 "In12.Cu" signal "L13GND")
		(2 "B.Cu" signal "BOTTOM")
		(9 "F.Adhes" user "F.Adhesive")
		(11 "B.Adhes" user "B.Adhesive")
		(13 "F.Paste" user "Package Geometry/Pastemask Top")
		(15 "B.Paste" user "Package Geometry/Pastemask Bottom")
		(5 "F.SilkS" user "Ref Des/Silkscreen Top")
		(7 "B.SilkS" user "Ref Des/Silkscreen Bottom")
		(1 "F.Mask" user "Board Geometry/Soldermask Top")
		(3 "B.Mask" user "Board Geometry/Soldermask Bottom")
		(17 "Dwgs.User" user "User.Drawings")
		(19 "Cmts.User" user "User.Comments")
		(21 "Eco1.User" user "User.Eco1")
		(23 "Eco2.User" user "User.Eco2")
		(25 "Edge.Cuts" user "Board Geometry/Outline")
		(27 "Margin" user)
		(31 "F.CrtYd" user "Package Geometry/Place Bound Top")
		(29 "B.CrtYd" user "Package Geometry/Place Bound Bottom")
		(35 "F.Fab" user "Ref Des/Assembly Top")
		(33 "B.Fab" user "Ref Des/Assembly Bottom")
	)
	(footprint ""
		(layer "B.Cu")
		(at 373.6975 -57.658 -90)
		(property "Reference" "R3P58"
			(at 0 0 90)
			(layer "B.SilkS")
			(hide yes)
			(effects
				(font
					(size 1.27 1.27)
				)
				(justify mirror)
			)
		)
		(property "Value" ""
			(at 0 0 90)
			(layer "B.Fab")
			(effects
				(font
					(size 1.27 1.27)
				)
				(justify mirror)
			)
		)
		(duplicate_pad_numbers_are_jumpers no)
		(fp_poly
			(pts
				(xy 0.2794 -0.1016) (xy -0.2794 -0.1016) (xy -0.2794 0.9906) (xy 0.2794 0.9906)
			)
			(stroke
				(width 0)
				(type default)
			)
			(fill no)
			(layer "B.CrtYd")
		)
		(fp_line
			(start -0.2794 0.9906)
			(end -0.2794 -0.1016)
			(stroke
				(width 0.1)
				(type default)
			)
			(layer "B.Fab")
		)
		(fp_line
			(start 0.2794 0.9906)
			(end -0.2794 0.9906)
			(stroke
				(width 0.1)
				(type default)
			)
			(layer "B.Fab")
		)
		(fp_line
			(start -0.2794 -0.1016)
			(end 0.2794 -0.1016)
			(stroke
				(width 0.1)
				(type default)
			)
			(layer "B.Fab")
		)
		(fp_line
			(start 0.2794 -0.1016)
			(end 0.2794 0.9906)
			(stroke
				(width 0.1)
				(type default)
			)
			(layer "B.Fab")
		)
		(pad "1" smd rect
			(at 0 0 90)
			(size 0.508 0.508)
			(layers "B.Cu" "B.Mask" "B.Paste")
			(net "H_CPU1_CATERR_G_N")
		)
		(pad "2" smd rect
			(at 0 0.889 90)
			(size 0.508 0.508)
			(layers "B.Cu" "B.Mask" "B.Paste")
			(net "H_CPU_CATERR_G_N")
		)
		(zone
			(layer "B.Cu")
			(hatch none 0.5)
			(connect_pads
				(clearance 0)
			)
			(min_thickness 0.25)
			(keepout
				(tracks not_allowed)
				(vias allowed)
				(pads allowed)
				(copperpour not_allowed)
				(footprints allowed)
			)
			(placement
				(enabled no)
				(sheetname "")
			)
			(fill
				(thermal_gap 0.5)
				(thermal_bridge_width 0.5)
				(island_removal_mode 0)
			)
			(polygon
				(pts
					(xy 373.0625 -57.404) (xy 373.0625 -57.912) (xy 373.4435 -57.912) (xy 373.4435 -57.404)
				)
			)
		)
		(zone
			(layer "B.Cu")
			(hatch none 0.5)
			(connect_pads
				(clearance 0)
			)
			(min_thickness 0.25)
			(keepout
				(tracks allowed)
				(vias not_allowed)
				(pads allowed)
				(copperpour not_allowed)
				(footprints allowed)
			)
			(placement
				(enabled no)
				(sheetname "")
			)
			(fill
				(thermal_gap 0.5)
				(thermal_bridge_width 0.5)
				(island_removal_mode 0)
			)
			(polygon
				(pts
					(xy 373.4435 -57.404) (xy 373.4435 -57.912) (xy 373.0625 -57.912) (xy 373.0625 -57.404)
				)
			)
		)
	)
	(footprint ""
		(layer "B.Cu")
		(at 340.331806 -61.257434)
		(property "Reference" "C2U8"
			(at 0 0 0)
			(layer "B.SilkS")
			(hide yes)
			(effects
				(font
					(size 1.27 1.27)
				)
				(justify mirror)
			)
		)
		(property "Value" ""
			(at 0 0 0)
			(layer "B.Fab")
			(effects
				(font
					(size 1.27 1.27)
				)
				(justify mirror)
			)
		)
		(duplicate_pad_numbers_are_jumpers no)
		(fp_poly
			(pts
				(xy -0.3048 -0.1016) (xy -0.3048 0.9906) (xy 0.3048 0.9906) (xy 0.3048 -0.1016)
			)
			(stroke
				(width 0)
				(type default)
			)
			(fill no)
			(layer "B.CrtYd")
		)
		(fp_line
			(start -0.3048 -0.1016)
			(end 0.3048 -0.1016)
			(stroke
				(width 0.1)
				(type default)
			)
			(layer "B.Fab")
		)
		(fp_line
			(start -0.3048 0.9906)
			(end -0.3048 -0.1016)
			(stroke
				(width 0.1)
				(type default)
			)
			(layer "B.Fab")
		)
		(fp_line
			(start 0.3048 -0.1016)
			(end 0.3048 0.9906)
			(stroke
				(width 0.1)
				(type default)
			)
			(layer "B.Fab")
		)
		(fp_line
			(start 0.3048 0.9906)
			(end -0.3048 0.9906)
			(stroke
				(width 0.1)
				(type default)
			)
			(layer "B.Fab")
		)
		(pad "1" smd rect
			(at 0 0 180)
			(size 0.508 0.508)
			(layers "B.Cu" "B.Mask" "B.Paste")
			(net "P3E_CPU0_PE1_PCH_RXN<2>")
		)
		(pad "2" smd rect
			(at 0 0.889 180)
			(size 0.508 0.508)
			(layers "B.Cu" "B.Mask" "B.Paste")
			(net "P3E_CPU0_PE1_SS_RXN<2>")
		)
		(zone
			(layer "B.Cu")
			(hatch none 0.5)
			(connect_pads
				(clearance 0)
			)
			(min_thickness 0.25)
			(keepout
				(tracks allowed)
				(vias not_allowed)
				(pads allowed)
				(copperpour not_allowed)
				(footprints allowed)
			)
			(placement
				(enabled no)
				(sheetname "")
			)
			(fill
				(thermal_gap 0.5)
				(thermal_bridge_width 0.5)
				(island_removal_mode 0)
			)
			(polygon
				(pts
					(xy 340.585806 -61.003434) (xy 340.077806 -61.003434) (xy 340.077806 -60.622434) (xy 340.585806 -60.622434)
				)
			)
		)
		(zone
			(layer "B.Cu")
			(hatch none 0.5)
			(connect_pads
				(clearance 0)
			)
			(min_thickness 0.25)
			(keepout
				(tracks not_allowed)
				(vias allowed)
				(pads allowed)
				(copperpour not_allowed)
				(footprints allowed)
			)
			(placement
				(enabled no)
				(sheetname "")
			)
			(fill
				(thermal_gap 0.5)
				(thermal_bridge_width 0.5)
				(island_removal_mode 0)
			)
			(polygon
				(pts
					(xy 340.585806 -60.622434) (xy 340.077806 -60.622434) (xy 340.077806 -61.003434) (xy 340.585806 -61.003434)
				)
			)
		)
	)
	(footprint ""
		(layer "B.Cu")
		(at 93.444568 -8.0772 -90)
		(property "Reference" "C8U9"
			(at 0 0 90)
			(layer "B.SilkS")
			(hide yes)
			(effects
				(font
					(size 1.27 1.27)
				)
				(justify mirror)
			)
		)
		(property "Value" ""
			(at 0 0 90)
			(layer "B.Fab")
			(effects
				(font
					(size 1.27 1.27)
				)
				(justify mirror)
			)
		)
		(duplicate_pad_numbers_are_jumpers no)
		(fp_rect
			(start 0.500126 1.598422)
			(end -0.500126 -0.201422)
			(stroke
				(width 0)
				(type default)
			)
			(fill no)
			(layer "B.CrtYd")
		)
		(fp_line
			(start -0.500126 1.598422)
			(end 0.500126 1.598422)
			(stroke
				(width 0.1)
				(type default)
			)
			(layer "B.Fab")
		)
		(fp_line
			(start 0.500126 1.598422)
			(end 0.500126 -0.201422)
			(stroke
				(width 0.1)
				(type default)
			)
			(layer "B.Fab")
		)
		(fp_line
			(start -0.500126 -0.201422)
			(end -0.500126 1.598422)
			(stroke
				(width 0.1)
				(type default)
			)
			(layer "B.Fab")
		)
		(fp_line
			(start 0.500126 -0.201422)
			(end -0.500126 -0.201422)
			(stroke
				(width 0.1)
				(type default)
			)
			(layer "B.Fab")
		)
		(pad "1" smd rect
			(at 0 0 180)
			(size 0.889 0.9906)
			(layers "B.Cu" "B.Mask" "B.Paste")
			(net "PVDDQ_GHJ")
		)
		(pad "2" smd rect
			(at 0 1.397 180)
			(size 0.889 0.9906)
			(layers "B.Cu" "B.Mask" "B.Paste")
			(net "GND")
		)
		(zone
			(layer "B.Cu")
			(hatch none 0.5)
			(connect_pads
				(clearance 0)
			)
			(min_thickness 0.25)
			(keepout
				(tracks allowed)
				(vias not_allowed)
				(pads allowed)
				(copperpour not_allowed)
				(footprints allowed)
			)
			(placement
				(enabled no)
				(sheetname "")
			)
			(fill
				(thermal_gap 0.5)
				(thermal_bridge_width 0.5)
				(island_removal_mode 0)
			)
			(polygon
				(pts
					(xy 92.492068 -7.5819) (xy 93.000068 -7.5819) (xy 93.000068 -8.5725) (xy 92.492068 -8.5725)
				)
			)
		)
		(zone
			(layer "B.Cu")
			(hatch none 0.5)
			(connect_pads
				(clearance 0)
			)
			(min_thickness 0.25)
			(keepout
				(tracks not_allowed)
				(vias allowed)
				(pads allowed)
				(copperpour not_allowed)
				(footprints allowed)
			)
			(placement
				(enabled no)
				(sheetname "")
			)
			(fill
				(thermal_gap 0.5)
				(thermal_bridge_width 0.5)
				(island_removal_mode 0)
			)
			(polygon
				(pts
					(xy 92.492068 -7.5819) (xy 93.000068 -7.5819) (xy 93.000068 -8.5725) (xy 92.492068 -8.5725)
				)
			)
		)
	)
	(footprint ""
		(layer "B.Cu")
		(at 458.08773 -18.55724)
		(property "Reference" "C2T9"
			(at 0 0 0)
			(layer "B.SilkS")
			(hide yes)
			(effects
				(font
					(size 1.27 1.27)
				)
				(justify mirror)
			)
		)
		(property "Value" ""
			(at 0 0 0)
			(layer "B.Fab")
			(effects
				(font
					(size 1.27 1.27)
				)
				(justify mirror)
			)
		)
		(duplicate_pad_numbers_are_jumpers no)
		(fp_poly
			(pts
				(xy 0.7239 -0.2159) (xy -0.7239 -0.2159) (xy -0.7239 1.9939) (xy 0.7239 1.9939)
			)
			(stroke
				(width 0)
				(type default)
			)
			(fill no)
			(layer "B.CrtYd")
		)
		(fp_line
			(start -0.7239 -0.2159)
			(end 0.7239 -0.2159)
			(stroke
				(width 0.1)
				(type default)
			)
			(layer "B.Fab")
		)
		(fp_line
			(start -0.7239 1.9939)
			(end -0.7239 -0.2159)
			(stroke
				(width 0.1)
				(type default)
			)
			(layer "B.Fab")
		)
		(fp_line
			(start 0.7239 -0.2159)
			(end 0.7239 1.9939)
			(stroke
				(width 0.1)
				(type default)
			)
			(layer "B.Fab")
		)
		(fp_line
			(start 0.7239 1.9939)
			(end -0.7239 1.9939)
			(stroke
				(width 0.1)
				(type default)
			)
			(layer "B.Fab")
		)
		(pad "1" smd rect
			(at 0 0 180)
			(size 1.27 1.016)
			(layers "B.Cu" "B.Mask" "B.Paste")
			(net "P3V3_STBY")
		)
		(pad "2" smd rect
			(at 0 1.778 180)
			(size 1.27 1.016)
			(layers "B.Cu" "B.Mask" "B.Paste")
			(net "GND")
		)
		(zone
			(layer "B.Cu")
			(hatch none 0.5)
			(connect_pads
				(clearance 0)
			)
			(min_thickness 0.25)
			(keepout
				(tracks not_allowed)
				(vias allowed)
				(pads allowed)
				(copperpour not_allowed)
				(footprints allowed)
			)
			(placement
				(enabled no)
				(sheetname "")
			)
			(fill
				(thermal_gap 0.5)
				(thermal_bridge_width 0.5)
				(island_removal_mode 0)
			)
			(polygon
				(pts
					(xy 458.72273 -18.04924) (xy 457.45273 -18.04924) (xy 457.45273 -17.28724) (xy 458.72273 -17.28724)
				)
			)
		)
	)
	(footprint ""
		(layer "B.Cu")
		(at 473.719652 -145.477484 -90)
		(property "Reference" "C6W1"
			(at 0.8382 -0.67818 270)
			(unlocked yes)
			(layer "B.SilkS")
			(effects
				(font
					(size 0.4064 0.254)
					(thickness 0.1524)
				)
				(justify left mirror)
			)
		)
		(property "Value" ""
			(at 0 0 90)
			(layer "B.Fab")
			(effects
				(font
					(size 1.27 1.27)
				)
				(justify mirror)
			)
		)
		(duplicate_pad_numbers_are_jumpers no)
		(fp_poly
			(pts
				(xy -0.3048 -0.1016) (xy -0.3048 0.9906) (xy 0.3048 0.9906) (xy 0.3048 -0.1016)
			)
			(stroke
				(width 0)
				(type default)
			)
			(fill no)
			(layer "B.CrtYd")
		)
		(fp_line
			(start -0.3048 0.9906)
			(end -0.3048 -0.1016)
			(stroke
				(width 0.1)
				(type default)
			)
			(layer "B.Fab")
		)
		(fp_line
			(start 0.3048 0.9906)
			(end -0.3048 0.9906)
			(stroke
				(width 0.1)
				(type default)
			)
			(layer "B.Fab")
		)
		(fp_line
			(start -0.3048 -0.1016)
			(end 0.3048 -0.1016)
			(stroke
				(width 0.1)
				(type default)
			)
			(layer "B.Fab")
		)
		(fp_line
			(start 0.3048 -0.1016)
			(end 0.3048 0.9906)
			(stroke
				(width 0.1)
				(type default)
			)
			(layer "B.Fab")
		)
		(pad "1" smd rect
			(at 0 0 90)
			(size 0.508 0.508)
			(layers "B.Cu" "B.Mask" "B.Paste")
			(net "P3V3_STBY")
		)
		(pad "2" smd rect
			(at 0 0.889 90)
			(size 0.508 0.508)
			(layers "B.Cu" "B.Mask" "B.Paste")
			(net "GND")
		)
		(zone
			(layer "B.Cu")
			(hatch none 0.5)
			(connect_pads
				(clearance 0)
			)
			(min_thickness 0.25)
			(keepout
				(tracks not_allowed)
				(vias allowed)
				(pads allowed)
				(copperpour not_allowed)
				(footprints allowed)
			)
			(placement
				(enabled no)
				(sheetname "")
			)
			(fill
				(thermal_gap 0.5)
				(thermal_bridge_width 0.5)
				(island_removal_mode 0)
			)
			(polygon
				(pts
					(xy 473.084652 -145.223484) (xy 473.084652 -145.731484) (xy 473.465652 -145.731484) (xy 473.465652 -145.223484)
				)
			)
		)
		(zone
			(layer "B.Cu")
			(hatch none 0.5)
			(connect_pads
				(clearance 0)
			)
			(min_thickness 0.25)
			(keepout
				(tracks allowed)
				(vias not_allowed)
				(pads allowed)
				(copperpour not_allowed)
				(footprints allowed)
			)
			(placement
				(enabled no)
				(sheetname "")
			)
			(fill
				(thermal_gap 0.5)
				(thermal_bridge_width 0.5)
				(island_removal_mode 0)
			)
			(polygon
				(pts
					(xy 473.465652 -145.223484) (xy 473.465652 -145.731484) (xy 473.084652 -145.731484) (xy 473.084652 -145.223484)
				)
			)
		)
	)
	(footprint ""
		(layer "B.Cu")
		(at 383.42824 -81.06918 90)
		(property "Reference" "R7D15"
			(at 0.8382 -0.67818 90)
			(unlocked yes)
			(layer "B.SilkS")
			(effects
				(font
					(size 0.4064 0.254)
					(thickness 0.1524)
				)
				(justify left mirror)
			)
		)
		(property "Value" ""
			(at 0 0 90)
			(layer "B.Fab")
			(effects
				(font
					(size 1.27 1.27)
				)
				(justify mirror)
			)
		)
		(duplicate_pad_numbers_are_jumpers no)
		(fp_poly
			(pts
				(xy 0.2794 -0.1016) (xy -0.2794 -0.1016) (xy -0.2794 0.9906) (xy 0.2794 0.9906)
			)
			(stroke
				(width 0)
				(type default)
			)
			(fill no)
			(layer "B.CrtYd")
		)
		(fp_line
			(start 0.2794 -0.1016)
			(end 0.2794 0.9906)
			(stroke
				(width 0.1)
				(type default)
			)
			(layer "B.Fab")
		)
		(fp_line
			(start -0.2794 -0.1016)
			(end 0.2794 -0.1016)
			(stroke
				(width 0.1)
				(type default)
			)
			(layer "B.Fab")
		)
		(fp_line
			(start 0.2794 0.9906)
			(end -0.2794 0.9906)
			(stroke
				(width 0.1)
				(type default)
			)
			(layer "B.Fab")
		)
		(fp_line
			(start -0.2794 0.9906)
			(end -0.2794 -0.1016)
			(stroke
				(width 0.1)
				(type default)
			)
			(layer "B.Fab")
		)
		(pad "1" smd rect
			(at 0 0 270)
			(size 0.508 0.508)
			(layers "B.Cu" "B.Mask" "B.Paste")
			(net "PECI_PCH")
		)
		(pad "2" smd rect
			(at 0 0.889 270)
			(size 0.508 0.508)
			(layers "B.Cu" "B.Mask" "B.Paste")
			(net "GND")
		)
		(zone
			(layer "B.Cu")
			(hatch none 0.5)
			(connect_pads
				(clearance 0)
			)
			(min_thickness 0.25)
			(keepout
				(tracks allowed)
				(vias not_allowed)
				(pads allowed)
				(copperpour not_allowed)
				(footprints allowed)
			)
			(placement
				(enabled no)
				(sheetname "")
			)
			(fill
				(thermal_gap 0.5)
				(thermal_bridge_width 0.5)
				(island_removal_mode 0)
			)
			(polygon
				(pts
					(xy 383.68224 -81.32318) (xy 383.68224 -80.81518) (xy 384.06324 -80.81518) (xy 384.06324 -81.32318)
				)
			)
		)
		(zone
			(layer "B.Cu")
			(hatch none 0.5)
			(connect_pads
				(clearance 0)
			)
			(min_thickness 0.25)
			(keepout
				(tracks not_allowed)
				(vias allowed)
				(pads allowed)
				(copperpour not_allowed)
				(footprints allowed)
			)
			(placement
				(enabled no)
				(sheetname "")
			)
			(fill
				(thermal_gap 0.5)
				(thermal_bridge_width 0.5)
				(island_removal_mode 0)
			)
			(polygon
				(pts
					(xy 384.06324 -81.32318) (xy 384.06324 -80.81518) (xy 383.68224 -80.81518) (xy 383.68224 -81.32318)
				)
			)
		)
	)
	(footprint ""
		(layer "B.Cu")
		(at 354.36429 -77.915516)
		(property "Reference" "C3P33"
			(at 0 0 0)
			(layer "B.SilkS")
			(hide yes)
			(effects
				(font
					(size 1.27 1.27)
				)
				(justify mirror)
			)
		)
		(property "Value" ""
			(at 0 0 0)
			(layer "B.Fab")
			(effects
				(font
					(size 1.27 1.27)
				)
				(justify mirror)
			)
		)
		(duplicate_pad_numbers_are_jumpers no)
		(fp_poly
			(pts
				(xy -0.3048 -0.1016) (xy -0.3048 0.9906) (xy 0.3048 0.9906) (xy 0.3048 -0.1016)
			)
			(stroke
				(width 0)
				(type default)
			)
			(fill no)
			(layer "B.CrtYd")
		)
		(fp_line
			(start -0.3048 -0.1016)
			(end 0.3048 -0.1016)
			(stroke
				(width 0.1)
				(type default)
			)
			(layer "B.Fab")
		)
		(fp_line
			(start -0.3048 0.9906)
			(end -0.3048 -0.1016)
			(stroke
				(width 0.1)
				(type default)
			)
			(layer "B.Fab")
		)
		(fp_line
			(start 0.3048 -0.1016)
			(end 0.3048 0.9906)
			(stroke
				(width 0.1)
				(type default)
			)
			(layer "B.Fab")
		)
		(fp_line
			(start 0.3048 0.9906)
			(end -0.3048 0.9906)
			(stroke
				(width 0.1)
				(type default)
			)
			(layer "B.Fab")
		)
		(pad "1" smd rect
			(at 0 0 180)
			(size 0.508 0.508)
			(layers "B.Cu" "B.Mask" "B.Paste")
			(net "P3E_CPU0_PE1_SS_TXN<5>")
		)
		(pad "2" smd rect
			(at 0 0.889 180)
			(size 0.508 0.508)
			(layers "B.Cu" "B.Mask" "B.Paste")
			(net "P3E_CPU0_PE1_SS_C_TXN<5>")
		)
		(zone
			(layer "B.Cu")
			(hatch none 0.5)
			(connect_pads
				(clearance 0)
			)
			(min_thickness 0.25)
			(keepout
				(tracks allowed)
				(vias not_allowed)
				(pads allowed)
				(copperpour not_allowed)
				(footprints allowed)
			)
			(placement
				(enabled no)
				(sheetname "")
			)
			(fill
				(thermal_gap 0.5)
				(thermal_bridge_width 0.5)
				(island_removal_mode 0)
			)
			(polygon
				(pts
					(xy 354.61829 -77.661516) (xy 354.11029 -77.661516) (xy 354.11029 -77.280516) (xy 354.61829 -77.280516)
				)
			)
		)
		(zone
			(layer "B.Cu")
			(hatch none 0.5)
			(connect_pads
				(clearance 0)
			)
			(min_thickness 0.25)
			(keepout
				(tracks not_allowed)
				(vias allowed)
				(pads allowed)
				(copperpour not_allowed)
				(footprints allowed)
			)
			(placement
				(enabled no)
				(sheetname "")
			)
			(fill
				(thermal_gap 0.5)
				(thermal_bridge_width 0.5)
				(island_removal_mode 0)
			)
			(polygon
				(pts
					(xy 354.61829 -77.280516) (xy 354.11029 -77.280516) (xy 354.11029 -77.661516) (xy 354.61829 -77.661516)
				)
			)
		)
	)
)
